FILE_TYPE = CONNECTIVITY;
{Allegro Design Entry HDL 16.6-p007 (v16-6-112F) 10/10/2012}
"PAGE_NUMBER" = 103;
0"NC";
1"GND\g";
2"GND\g";
3"GND\g";
4"GND\g";
5"GND\g";
6"GND\g";
7"GND\g";
8"GND\g";
9"GND\g";
10"GND\g";
11"GND\g";
12"GND\g";
13"GND\g";
14"GND\g";
15"GND\g";
16"GND\g";
17"GND\g";
18"GND\g";
19"GND\g";
20"GND\g";
21"GND\g";
22"GND\g";
23"GND\g";
24"GND\g";
25"CLK_100M_CPU0_BCLK1_DP";
26"CLK_100M_CPU0_RC_REFCLK0_R_DN";
27"CLK_100M_CPU1_PE_REFCLK_DP";
28"CLK_100M_CPU1_RC_REFCLK0_DP";
29"CLK_100M_CPU0_RC_REFCLK1_DN";
30"CLK_100M_CPU0_RC_REFCLK1_R_DN";
31"CLK_100M_CPU1_RC_REFCLK1_DP";
32"CLK_100M_CPU1_RC_REFCLK0_R_DP";
33"CLK_100M_CPU0_RC_REFCLK0_DP";
34"CLK_100M_CPU0_RC_REFCLK1_DP";
35"CLK_100M_CPU0_BCLK2_DN";
36"CLK_100M_CPU0_BCLK2_DP";
37"CLK_100M_CPU0_PE_REFCLK_DN";
38"CLK_100M_CPU0_PE_REFCLK_DP";
39"CLK_100M_CPU0_RC_REFCLK0_DN";
40"CLK_100M_CPU0_BCLK0_DN";
41"CLK_100M_CPU0_BCLK0_DP";
42"CLK_100M_CPU0_BCLK1_DN";
43"CLK_100M_CPU0_PE_REFCLK_R_DN";
44"CLK_100M_CPU0_BCLK2_R_DP";
45"CLK_100M_CPU0_BCLK2_R_DN";
46"CLK_100M_CPU0_BCLK1_R_DP";
47"CLK_100M_CPU0_BCLK1_R_DN";
48"CLK_100M_CPU0_BCLK0_R_DN";
49"CLK_100M_CPU0_BCLK0_R_DP";
50"CLK_100M_CPU0_RC_REFCLK1_R_DP";
51"CLK_100M_CPU0_RC_REFCLK0_R_DP";
52"CLK_100M_CPU0_PE_REFCLK_R_DP";
53"CLK_100M_CPU1_RC_REFCLK1_DN";
54"CLK_100M_CPU1_BCLK1_DP";
55"CLK_100M_CPU1_BCLK2_DN";
56"CLK_100M_CPU1_BCLK2_DP";
57"CLK_100M_CPU1_PE_REFCLK_DN";
58"CLK_100M_CPU1_RC_REFCLK0_DN";
59"CLK_100M_CPU1_BCLK0_DN";
60"CLK_100M_CPU1_BCLK0_DP";
61"CLK_100M_CPU1_BCLK1_DN";
62"CLK_100M_CPU1_RC_REFCLK1_R_DP";
63"CLK_100M_CPU1_RC_REFCLK1_R_DN";
64"CLK_100M_CPU1_RC_REFCLK0_R_DN";
65"CLK_100M_CPU1_PE_REFCLK_R_DP";
66"CLK_100M_CPU1_PE_REFCLK_R_DN";
67"CLK_100M_CPU1_BCLK2_R_DP";
68"CLK_100M_CPU1_BCLK2_R_DN";
69"CLK_100M_CPU1_BCLK1_R_DP";
70"CLK_100M_CPU1_BCLK1_R_DN";
71"CLK_100M_CPU1_BCLK0_R_DP";
72"CLK_100M_CPU1_BCLK0_R_DN";
%"RES"
"1","(300,1250)","0","mstr_discrete","I1";
;
CDS_SEC"1"
VALUE"27.4"
WATTAGE"1/16W"
LOCATION"R4D25"
TOLERANCE"1%"
PACK_TYPE"0402"
MATERIAL"CHIP"
PART_NUMBER"G21796-182"
ROOM"DB1200Z"
CDS_LOCATION"R4D25"
SEC"1"
SEC_TYPE"0402"
CDS_LIB"mstr_discrete"
BOM_COST"SYS_CLOCK";
"B"
$PN"2"40;
"A"
$PN"1"48;
%"RES"
"1","(300,2875)","0","mstr_discrete","I104";
;
CDS_SEC"1"
VALUE"27.4"
WATTAGE"1/16W"
LOCATION"R4D17"
TOLERANCE"1%"
PACK_TYPE"0402"
MATERIAL"CHIP"
PART_NUMBER"G21796-182"
ROOM"DB1200Z"
CDS_LOCATION"R4D17"
CDS_LIB"mstr_discrete"
BOM_COST"SYS_CLOCK"
SEC_TYPE"0402"
SEC"1";
"B"
$PN"2"36;
"A"
$PN"1"44;
%"RES"
"1","(300,2550)","0","mstr_discrete","I109";
;
CDS_SEC"1"
VALUE"27.4"
WATTAGE"1/16W"
MATERIAL"CHIP"
PACK_TYPE"0402"
TOLERANCE"1%"
LOCATION"R4D14"
PART_NUMBER"G21796-182"
CDS_LIB"mstr_discrete"
SEC_TYPE"0402"
ROOM"DB1200Z"
BOM_COST"SYS_CLOCK"
SEC"1"
CDS_LOCATION"R4D14";
"B"
$PN"2"35;
"A"
$PN"1"45;
%"RES"
"1","(300,2225)","0","mstr_discrete","I114";
;
CDS_SEC"1"
VALUE"27.4"
WATTAGE"1/16W"
LOCATION"R4D22"
MATERIAL"CHIP"
PACK_TYPE"0402"
TOLERANCE"1%"
PART_NUMBER"G21796-182"
CDS_LOCATION"R4D22"
SEC_TYPE"0402"
BOM_COST"SYS_CLOCK"
SEC"1"
ROOM"DB1200Z"
CDS_LIB"mstr_discrete";
"B"
$PN"2"25;
"A"
$PN"1"46;
%"RES"
"1","(300,1900)","0","mstr_discrete","I119";
;
CDS_SEC"1"
VALUE"27.4"
WATTAGE"1/16W"
LOCATION"R4D20"
MATERIAL"CHIP"
PACK_TYPE"0402"
TOLERANCE"1%"
PART_NUMBER"G21796-182"
CDS_LOCATION"R4D20"
CDS_LIB"mstr_discrete"
SEC_TYPE"0402"
BOM_COST"SYS_CLOCK"
SEC"1"
ROOM"DB1200Z";
"B"
$PN"2"42;
"A"
$PN"1"47;
%"RES"
"1","(-3325,4800)","0","mstr_discrete","I121";
;
CDS_SEC"1"
WATTAGE"1/16W"
VALUE"42.2"
PART_NUMBER"G21796-259"
LOCATION"R7P9"
TOLERANCE"1.0%"
MATERIAL"EMPTY"
PACK_TYPE"0402"
CDS_LOCATION"R7P9"
ROOM"DB1200Z"
SEC"1"
SEC_TYPE"0402"
CDS_LIB"mstr_discrete"
BOM_COST"SYS_CLOCK";
"B"
$PN"2"24;
"A"
$PN"1"31;
%"RES"
"1","(-3300,4425)","0","mstr_discrete","I123";
;
CDS_SEC"1"
WATTAGE"1/16W"
VALUE"42.2"
LOCATION"R7P12"
TOLERANCE"1.0%"
MATERIAL"EMPTY"
PART_NUMBER"G21796-259"
PACK_TYPE"0402"
CDS_LOCATION"R7P12"
CDS_LIB"mstr_discrete"
ROOM"DB1200Z"
SEC"1"
SEC_TYPE"0402"
BOM_COST"SYS_CLOCK";
"B"
$PN"2"23;
"A"
$PN"1"53;
%"RES"
"1","(-3325,4075)","0","mstr_discrete","I125";
;
CDS_SEC"1"
WATTAGE"1/16W"
VALUE"42.2"
TOLERANCE"1.0%"
MATERIAL"EMPTY"
PACK_TYPE"0402"
PART_NUMBER"G21796-259"
LOCATION"R7P6"
CDS_LIB"mstr_discrete"
SEC_TYPE"0402"
SEC"1"
CDS_LOCATION"R7P6"
ROOM"DB1200Z"
BOM_COST"SYS_CLOCK";
"B"
$PN"2"1;
"A"
$PN"1"28;
%"GND"
"1","(-2800,3975)","0","mstr_symbols","I126";
;
VOLTAGE"0.0V"
SIZE"1B"
CDS_LIB"mstr_symbols"
BODY_TYPE"PLUMBING"
HDL_POWER"GND";
"A\NAC"1;
%"RES"
"1","(-3325,3750)","0","mstr_discrete","I127";
;
WATTAGE"1/16W"
VALUE"42.2"
LOCATION"R7P7"
TOLERANCE"1.0%"
MATERIAL"EMPTY"
PACK_TYPE"0402"
PART_NUMBER"G21796-259"
CDS_LOCATION"R7P7"
ROOM"DB1200Z"
$SEC"1"
CDS_SEC"1"
BOM_COST"SYS_CLOCK"
CDS_LIB"mstr_discrete";
"B"
$PN"2"2;
"A"
$PN"1"58;
%"GND"
"1","(-2800,3650)","0","mstr_symbols","I128";
;
VOLTAGE"0.0V"
SIZE"1B"
CDS_LIB"mstr_symbols"
BODY_TYPE"PLUMBING"
HDL_POWER"GND";
"A\NAC"2;
%"RES"
"1","(-3325,3425)","0","mstr_discrete","I129";
;
CDS_SEC"1"
WATTAGE"1/16W"
VALUE"42.2"
LOCATION"R7P3"
MATERIAL"EMPTY"
TOLERANCE"1.0%"
PACK_TYPE"0402"
PART_NUMBER"G21796-259"
CDS_LOCATION"R7P3"
CDS_LIB"mstr_discrete"
ROOM"DB1200Z"
SEC"1"
SEC_TYPE"0402"
BOM_COST"SYS_CLOCK";
"B"
$PN"2"3;
"A"
$PN"1"27;
%"GND"
"1","(-2800,3325)","0","mstr_symbols","I130";
;
VOLTAGE"0.0V"
SIZE"1B"
CDS_LIB"mstr_symbols"
BODY_TYPE"PLUMBING"
HDL_POWER"GND";
"A\NAC"3;
%"RES"
"1","(-3325,3100)","0","mstr_discrete","I131";
;
CDS_SEC"1"
WATTAGE"1/16W"
VALUE"42.2"
TOLERANCE"1.0%"
MATERIAL"EMPTY"
LOCATION"R7P4"
PACK_TYPE"0402"
PART_NUMBER"G21796-259"
CDS_LOCATION"R7P4"
ROOM"DB1200Z"
SEC"1"
SEC_TYPE"0402"
BOM_COST"SYS_CLOCK"
CDS_LIB"mstr_discrete";
"B"
$PN"2"4;
"A"
$PN"1"57;
%"GND"
"1","(-2800,3000)","0","mstr_symbols","I132";
;
VOLTAGE"0.0V"
SIZE"1B"
CDS_LIB"mstr_symbols"
BODY_TYPE"PLUMBING"
HDL_POWER"GND";
"A\NAC"4;
%"RES"
"1","(-3325,2775)","0","mstr_discrete","I133";
;
CDS_SEC"1"
WATTAGE"1/16W"
VALUE"42.2"
LOCATION"R7P1"
TOLERANCE"1.0%"
MATERIAL"EMPTY"
PACK_TYPE"0402"
PART_NUMBER"G21796-259"
CDS_LOCATION"R7P1"
ROOM"DB1200Z"
SEC"1"
SEC_TYPE"0402"
CDS_LIB"mstr_discrete"
BOM_COST"SYS_CLOCK";
"B"
$PN"2"5;
"A"
$PN"1"56;
%"GND"
"1","(-2800,2675)","0","mstr_symbols","I134";
;
VOLTAGE"0.0V"
CDS_LIB"mstr_symbols"
SIZE"1B"
BODY_TYPE"PLUMBING"
HDL_POWER"GND";
"A\NAC"5;
%"RES"
"1","(-3325,2450)","0","mstr_discrete","I135";
;
CDS_SEC"1"
WATTAGE"1/16W"
VALUE"42.2"
LOCATION"R7P2"
MATERIAL"EMPTY"
TOLERANCE"1.0%"
PACK_TYPE"0402"
PART_NUMBER"G21796-259"
CDS_LOCATION"R7P2"
CDS_LIB"mstr_discrete"
SEC"1"
ROOM"DB1200Z"
SEC_TYPE"0402"
BOM_COST"SYS_CLOCK";
"B"
$PN"2"6;
"A"
$PN"1"55;
%"GND"
"1","(-2800,2350)","0","mstr_symbols","I136";
;
VOLTAGE"0.0V"
SIZE"1B"
CDS_LIB"mstr_symbols"
BODY_TYPE"PLUMBING"
HDL_POWER"GND";
"A\NAC"6;
%"RES"
"1","(-3325,2125)","0","mstr_discrete","I137";
;
CDS_SEC"1"
WATTAGE"1/16W"
MATERIAL"EMPTY"
PACK_TYPE"0402"
TOLERANCE"1.0%"
VALUE"42.2"
LOCATION"R6P7"
PART_NUMBER"G21796-259"
CDS_LOCATION"R6P7"
ROOM"DB1200Z"
SEC"1"
SEC_TYPE"0402"
BOM_COST"SYS_CLOCK"
CDS_LIB"mstr_discrete";
"B"
$PN"2"7;
"A"
$PN"1"54;
%"GND"
"1","(-2800,2025)","0","mstr_symbols","I138";
;
VOLTAGE"0.0V"
SIZE"1B"
CDS_LIB"mstr_symbols"
BODY_TYPE"PLUMBING"
HDL_POWER"GND";
"A\NAC"7;
%"RES"
"1","(-3325,1800)","0","mstr_discrete","I139";
;
CDS_SEC"1"
WATTAGE"1/16W"
VALUE"42.2"
LOCATION"R6P8"
TOLERANCE"1.0%"
MATERIAL"EMPTY"
PACK_TYPE"0402"
PART_NUMBER"G21796-259"
CDS_LOCATION"R6P8"
ROOM"DB1200Z"
SEC_TYPE"0402"
SEC"1"
CDS_LIB"mstr_discrete"
BOM_COST"SYS_CLOCK";
"B"
$PN"2"8;
"A"
$PN"1"61;
%"RES"
"1","(-3925,4525)","0","mstr_discrete","I14";
;
CDS_SEC"1"
VALUE"27.4"
WATTAGE"1/16W"
TOLERANCE"1%"
MATERIAL"CHIP"
PACK_TYPE"0402"
PART_NUMBER"G21796-182"
LOCATION"R4D28"
CDS_LOCATION"R4D28"
CDS_LIB"mstr_discrete"
ROOM"DB1200Z"
SEC"1"
BOM_COST"SYS_CLOCK"
SEC_TYPE"0402";
"B"
$PN"2"53;
"A"
$PN"1"63;
%"GND"
"1","(-2800,1700)","0","mstr_symbols","I140";
;
VOLTAGE"0.0V"
SIZE"1B"
CDS_LIB"mstr_symbols"
BODY_TYPE"PLUMBING"
HDL_POWER"GND";
"A\NAC"8;
%"RES"
"1","(-3325,1475)","0","mstr_discrete","I141";
;
CDS_SEC"1"
WATTAGE"1/16W"
VALUE"42.2"
TOLERANCE"1.0%"
MATERIAL"EMPTY"
LOCATION"R6P5"
PACK_TYPE"0402"
PART_NUMBER"G21796-259"
CDS_LIB"mstr_discrete"
CDS_LOCATION"R6P5"
ROOM"DB1200Z"
SEC"1"
SEC_TYPE"0402"
BOM_COST"SYS_CLOCK";
"B"
$PN"2"9;
"A"
$PN"1"60;
%"GND"
"1","(-2800,1375)","0","mstr_symbols","I142";
;
VOLTAGE"0.0V"
SIZE"1B"
CDS_LIB"mstr_symbols"
BODY_TYPE"PLUMBING"
HDL_POWER"GND";
"A\NAC"9;
%"RES"
"1","(-3325,1150)","0","mstr_discrete","I143";
;
CDS_SEC"1"
WATTAGE"1/16W"
MATERIAL"EMPTY"
VALUE"42.2"
LOCATION"R6P6"
TOLERANCE"1.0%"
PACK_TYPE"0402"
PART_NUMBER"G21796-259"
CDS_LOCATION"R6P6"
ROOM"DB1200Z"
SEC"1"
SEC_TYPE"0402"
BOM_COST"SYS_CLOCK"
CDS_LIB"mstr_discrete";
"B"
$PN"2"10;
"A"
$PN"1"59;
%"GND"
"1","(-2800,1050)","0","mstr_symbols","I144";
;
VOLTAGE"0.0V"
SIZE"1B"
CDS_LIB"mstr_symbols"
BODY_TYPE"PLUMBING"
HDL_POWER"GND";
"A\NAC"10;
%"RES"
"1","(1025,4725)","0","mstr_discrete","I145";
;
CDS_SEC"1"
WATTAGE"1/16W"
VALUE"42.2"
LOCATION"R6P3"
MATERIAL"EMPTY"
TOLERANCE"1.0%"
PART_NUMBER"G21796-259"
PACK_TYPE"0402"
CDS_LOCATION"R6P3"
ROOM"DB1200Z"
SEC"1"
BOM_COST"SYS_CLOCK"
SEC_TYPE"0402"
CDS_LIB"mstr_discrete";
"B"
$PN"2"11;
"A"
$PN"1"34;
%"GND"
"1","(1550,4625)","0","mstr_symbols","I146";
;
VOLTAGE"0.0V"
SIZE"1B"
CDS_LIB"mstr_symbols"
BODY_TYPE"PLUMBING"
HDL_POWER"GND";
"A\NAC"11;
%"RES"
"1","(1050,4400)","0","mstr_discrete","I147";
;
CDS_SEC"1"
WATTAGE"1/16W"
VALUE"42.2"
LOCATION"R6P4"
TOLERANCE"1.0%"
MATERIAL"EMPTY"
PART_NUMBER"G21796-259"
PACK_TYPE"0402"
CDS_LOCATION"R6P4"
ROOM"DB1200Z"
SEC"1"
SEC_TYPE"0402"
BOM_COST"SYS_CLOCK"
CDS_LIB"mstr_discrete";
"B"
$PN"2"12;
"A"
$PN"1"29;
%"GND"
"1","(1575,4300)","0","mstr_symbols","I148";
;
VOLTAGE"0.0V"
SIZE"1B"
CDS_LIB"mstr_symbols"
BODY_TYPE"PLUMBING"
HDL_POWER"GND";
"A\NAC"12;
%"RES"
"1","(1025,4075)","0","mstr_discrete","I149";
;
CDS_SEC"1"
MATERIAL"EMPTY"
WATTAGE"1/16W"
VALUE"42.2"
TOLERANCE"1.0%"
PACK_TYPE"0402"
PART_NUMBER"G21796-259"
LOCATION"R6P1"
CDS_LIB"mstr_discrete"
CDS_LOCATION"R6P1"
ROOM"DB1200Z"
SEC"1"
SEC_TYPE"0402"
BOM_COST"SYS_CLOCK";
"B"
$PN"2"13;
"A"
$PN"1"33;
%"GND"
"1","(1550,3975)","0","mstr_symbols","I150";
;
VOLTAGE"0.0V"
SIZE"1B"
CDS_LIB"mstr_symbols"
BODY_TYPE"PLUMBING"
HDL_POWER"GND";
"A\NAC"13;
%"RES"
"1","(1050,3750)","0","mstr_discrete","I151";
;
CDS_SEC"1"
WATTAGE"1/16W"
VALUE"42.2"
LOCATION"R6P2"
TOLERANCE"1.0%"
MATERIAL"EMPTY"
PART_NUMBER"G21796-259"
PACK_TYPE"0402"
CDS_LOCATION"R6P2"
ROOM"DB1200Z"
SEC"1"
SEC_TYPE"0402"
BOM_COST"SYS_CLOCK"
CDS_LIB"mstr_discrete";
"B"
$PN"2"14;
"A"
$PN"1"39;
%"GND"
"1","(1575,3650)","0","mstr_symbols","I152";
;
VOLTAGE"0.0V"
SIZE"1B"
CDS_LIB"mstr_symbols"
BODY_TYPE"PLUMBING"
HDL_POWER"GND";
"A\NAC"14;
%"RES"
"1","(1050,3425)","0","mstr_discrete","I153";
;
CDS_SEC"1"
WATTAGE"1/16W"
VALUE"42.2"
LOCATION"R6P11"
MATERIAL"EMPTY"
TOLERANCE"1.0%"
PART_NUMBER"G21796-259"
PACK_TYPE"0402"
CDS_LOCATION"R6P11"
ROOM"DB1200Z"
SEC"1"
SEC_TYPE"0402"
BOM_COST"SYS_CLOCK"
CDS_LIB"mstr_discrete";
"B"
$PN"2"15;
"A"
$PN"1"38;
%"GND"
"1","(1575,3325)","0","mstr_symbols","I154";
;
VOLTAGE"0.0V"
SIZE"1B"
CDS_LIB"mstr_symbols"
BODY_TYPE"PLUMBING"
HDL_POWER"GND";
"A\NAC"15;
%"RES"
"1","(1075,3100)","0","mstr_discrete","I155";
;
CDS_SEC"1"
WATTAGE"1/16W"
VALUE"42.2"
TOLERANCE"1.0%"
MATERIAL"EMPTY"
PACK_TYPE"0402"
LOCATION"R6P9"
PART_NUMBER"G21796-259"
CDS_LOCATION"R6P9"
CDS_LIB"mstr_discrete"
ROOM"DB1200Z"
SEC"1"
SEC_TYPE"0402"
BOM_COST"SYS_CLOCK";
"B"
$PN"2"16;
"A"
$PN"1"37;
%"GND"
"1","(1600,3000)","0","mstr_symbols","I156";
;
CDS_LIB"mstr_symbols"
SIZE"1B"
VOLTAGE"0.0V"
BODY_TYPE"PLUMBING"
HDL_POWER"GND";
"A\NAC"16;
%"RES"
"1","(1050,2775)","0","mstr_discrete","I157";
;
CDS_SEC"1"
WATTAGE"1/16W"
VALUE"42.2"
LOCATION"R6P13"
TOLERANCE"1.0%"
MATERIAL"EMPTY"
PART_NUMBER"G21796-259"
PACK_TYPE"0402"
SEC_TYPE"0402"
SEC"1"
CDS_LOCATION"R6P13"
ROOM"DB1200Z"
BOM_COST"SYS_CLOCK"
CDS_LIB"mstr_discrete";
"B"
$PN"2"17;
"A"
$PN"1"36;
%"GND"
"1","(1575,2675)","0","mstr_symbols","I158";
;
VOLTAGE"0.0V"
SIZE"1B"
CDS_LIB"mstr_symbols"
BODY_TYPE"PLUMBING"
HDL_POWER"GND";
"A\NAC"17;
%"RES"
"1","(1050,2450)","0","mstr_discrete","I159";
;
CDS_SEC"1"
WATTAGE"1/16W"
VALUE"42.2"
LOCATION"R6P12"
MATERIAL"EMPTY"
TOLERANCE"1.0%"
PART_NUMBER"G21796-259"
PACK_TYPE"0402"
CDS_LOCATION"R6P12"
SEC"1"
ROOM"DB1200Z"
SEC_TYPE"0402"
BOM_COST"SYS_CLOCK"
CDS_LIB"mstr_discrete";
"B"
$PN"2"18;
"A"
$PN"1"35;
%"GND"
"1","(1575,2350)","0","mstr_symbols","I160";
;
VOLTAGE"0.0V"
SIZE"1B"
CDS_LIB"mstr_symbols"
BODY_TYPE"PLUMBING"
HDL_POWER"GND";
"A\NAC"18;
%"RES"
"1","(1050,2125)","0","mstr_discrete","I161";
;
CDS_SEC"1"
WATTAGE"1/16W"
MATERIAL"EMPTY"
PACK_TYPE"0402"
TOLERANCE"1.0%"
VALUE"42.2"
LOCATION"R4D24"
PART_NUMBER"G21796-259"
CDS_LOCATION"R4D24"
ROOM"DB1200Z"
SEC"1"
SEC_TYPE"0402"
BOM_COST"SYS_CLOCK"
CDS_LIB"mstr_discrete";
"B"
$PN"2"19;
"A"
$PN"1"25;
%"GND"
"1","(1575,2025)","0","mstr_symbols","I162";
;
VOLTAGE"0.0V"
SIZE"1B"
CDS_LIB"mstr_symbols"
BODY_TYPE"PLUMBING"
HDL_POWER"GND";
"A\NAC"19;
%"RES"
"1","(1050,1800)","0","mstr_discrete","I163";
;
CDS_SEC"1"
WATTAGE"1/16W"
VALUE"42.2"
LOCATION"R4D18"
TOLERANCE"1.0%"
MATERIAL"EMPTY"
PART_NUMBER"G21796-259"
PACK_TYPE"0402"
CDS_LOCATION"R4D18"
ROOM"DB1200Z"
SEC_TYPE"0402"
SEC"1"
CDS_LIB"mstr_discrete"
BOM_COST"SYS_CLOCK";
"B"
$PN"2"20;
"A"
$PN"1"42;
%"GND"
"1","(1575,1700)","0","mstr_symbols","I164";
;
VOLTAGE"0.0V"
CDS_LIB"mstr_symbols"
SIZE"1B"
BODY_TYPE"PLUMBING"
HDL_POWER"GND";
"A\NAC"20;
%"RES"
"1","(1050,1475)","0","mstr_discrete","I165";
;
CDS_SEC"1"
WATTAGE"1/16W"
VALUE"42.2"
LOCATION"R6P17"
TOLERANCE"1.0%"
MATERIAL"EMPTY"
PART_NUMBER"G21796-259"
PACK_TYPE"0402"
CDS_LOCATION"R6P17"
ROOM"DB1200Z"
SEC"1"
SEC_TYPE"0402"
BOM_COST"SYS_CLOCK"
CDS_LIB"mstr_discrete";
"B"
$PN"2"21;
"A"
$PN"1"41;
%"GND"
"1","(1575,1375)","0","mstr_symbols","I166";
;
VOLTAGE"0.0V"
SIZE"1B"
CDS_LIB"mstr_symbols"
BODY_TYPE"PLUMBING"
HDL_POWER"GND";
"A\NAC"21;
%"RES"
"1","(1050,1150)","0","mstr_discrete","I167";
;
CDS_SEC"1"
WATTAGE"1/16W"
VALUE"42.2"
LOCATION"R6P15"
PACK_TYPE"0402"
MATERIAL"EMPTY"
TOLERANCE"1.0%"
PART_NUMBER"G21796-259"
CDS_LOCATION"R6P15"
ROOM"DB1200Z"
SEC"1"
SEC_TYPE"0402"
BOM_COST"SYS_CLOCK"
CDS_LIB"mstr_discrete";
"B"
$PN"2"22;
"A"
$PN"1"40;
%"GND"
"1","(1575,1050)","0","mstr_symbols","I168";
;
VOLTAGE"0.0V"
SIZE"1B"
CDS_LIB"mstr_symbols"
BODY_TYPE"PLUMBING"
HDL_POWER"GND";
"A\NAC"22;
%"GND"
"1","(-2775,4325)","0","mstr_symbols","I169";
;
VOLTAGE"0.0V"
SIZE"1B"
CDS_LIB"mstr_symbols"
BODY_TYPE"PLUMBING"
HDL_POWER"GND";
"A\NAC"23;
%"GND"
"1","(-2800,4700)","0","mstr_symbols","I170";
;
VOLTAGE"0.0V"
SIZE"1B"
CDS_LIB"mstr_symbols"
BODY_TYPE"PLUMBING"
HDL_POWER"GND";
"A\NAC"24;
%"RES"
"1","(-3925,4175)","0","mstr_discrete","I19";
;
CDS_SEC"1"
VALUE"27.4"
WATTAGE"1/16W"
PACK_TYPE"0402"
TOLERANCE"1%"
MATERIAL"CHIP"
LOCATION"R4D19"
PART_NUMBER"G21796-182"
CDS_LOCATION"R4D19"
CDS_LIB"mstr_discrete"
ROOM"DB1200Z"
BOM_COST"SYS_CLOCK"
SEC_TYPE"0402"
SEC"1";
"B"
$PN"2"28;
"A"
$PN"1"32;
%"RES"
"1","(-3925,3850)","0","mstr_discrete","I24";
;
CDS_SEC"1"
VALUE"27.4"
WATTAGE"1/16W"
TOLERANCE"1%"
MATERIAL"CHIP"
PACK_TYPE"0402"
LOCATION"R4D21"
PART_NUMBER"G21796-182"
ROOM"DB1200Z"
CDS_LOCATION"R4D21"
SEC"1"
SEC_TYPE"0402"
CDS_LIB"mstr_discrete"
BOM_COST"SYS_CLOCK";
"B"
$PN"2"58;
"A"
$PN"1"64;
%"RES"
"1","(-3925,3525)","0","mstr_discrete","I29";
;
CDS_SEC"1"
VALUE"27.4"
WATTAGE"1/16W"
TOLERANCE"1%"
MATERIAL"CHIP"
PACK_TYPE"0402"
LOCATION"R4D13"
PART_NUMBER"G21796-182"
CDS_LIB"mstr_discrete"
CDS_LOCATION"R4D13"
ROOM"DB1200Z"
SEC"1"
SEC_TYPE"0402"
BOM_COST"SYS_CLOCK";
"B"
$PN"2"27;
"A"
$PN"1"65;
%"RES"
"1","(-3925,3200)","0","mstr_discrete","I34";
;
CDS_SEC"1"
VALUE"27.4"
WATTAGE"1/16W"
TOLERANCE"1%"
MATERIAL"CHIP"
PACK_TYPE"0402"
LOCATION"R4D16"
PART_NUMBER"G21796-182"
CDS_LOCATION"R4D16"
CDS_LIB"mstr_discrete"
SEC_TYPE"0402"
BOM_COST"SYS_CLOCK"
SEC"1"
ROOM"DB1200Z";
"B"
$PN"2"57;
"A"
$PN"1"66;
%"RES"
"1","(-3925,2875)","0","mstr_discrete","I39";
;
CDS_SEC"1"
VALUE"27.4"
WATTAGE"1/16W"
TOLERANCE"1%"
LOCATION"R4D9"
MATERIAL"CHIP"
PACK_TYPE"0402"
PART_NUMBER"G21796-182"
CDS_LOCATION"R4D9"
ROOM"DB1200Z"
CDS_LIB"mstr_discrete"
SEC_TYPE"0402"
BOM_COST"SYS_CLOCK"
SEC"1";
"B"
$PN"2"56;
"A"
$PN"1"67;
%"RES"
"1","(-3925,2550)","0","mstr_discrete","I44";
;
CDS_SEC"1"
VALUE"27.4"
WATTAGE"1/16W"
TOLERANCE"1%"
MATERIAL"CHIP"
PACK_TYPE"0402"
LOCATION"R4D11"
PART_NUMBER"G21796-182"
CDS_LIB"mstr_discrete"
SEC"1"
ROOM"DB1200Z"
CDS_LOCATION"R4D11"
SEC_TYPE"0402"
BOM_COST"SYS_CLOCK";
"B"
$PN"2"55;
"A"
$PN"1"68;
%"RES"
"1","(-3925,2225)","0","mstr_discrete","I49";
;
VALUE"27.4"
WATTAGE"1/16W"
LOCATION"R4D2"
TOLERANCE"1%"
MATERIAL"CHIP"
PACK_TYPE"0402"
PART_NUMBER"G21796-182"
CDS_LOCATION"R4D2"
CDS_LIB"mstr_discrete"
ROOM"DB1200Z"
$SEC"1"
CDS_SEC"1"
BOM_COST"SYS_CLOCK";
"B"
$PN"2"54;
"A"
$PN"1"69;
%"RES"
"1","(-3925,1900)","0","mstr_discrete","I54";
;
CDS_SEC"1"
VALUE"27.4"
LOCATION"R4D1"
WATTAGE"1/16W"
TOLERANCE"1%"
MATERIAL"CHIP"
PACK_TYPE"0402"
PART_NUMBER"G21796-182"
CDS_LOCATION"R4D1"
CDS_LIB"mstr_discrete"
SEC_TYPE"0402"
BOM_COST"SYS_CLOCK"
ROOM"DB1200Z"
SEC"1";
"B"
$PN"2"61;
"A"
$PN"1"70;
%"RES"
"1","(-3925,1575)","0","mstr_discrete","I59";
;
CDS_SEC"1"
VALUE"27.4"
WATTAGE"1/16W"
TOLERANCE"1%"
PACK_TYPE"0402"
MATERIAL"CHIP"
LOCATION"R4D4"
PART_NUMBER"G21796-182"
CDS_LOCATION"R4D4"
ROOM"DB1200Z"
CDS_LIB"mstr_discrete"
SEC"1"
SEC_TYPE"0402"
BOM_COST"SYS_CLOCK";
"B"
$PN"2"60;
"A"
$PN"1"71;
%"RES"
"1","(-3925,1250)","0","mstr_discrete","I64";
;
CDS_SEC"1"
VALUE"27.4"
WATTAGE"1/16W"
TOLERANCE"1%"
LOCATION"R4D3"
PACK_TYPE"0402"
MATERIAL"CHIP"
PART_NUMBER"G21796-182"
CDS_LIB"mstr_discrete"
ROOM"DB1200Z"
CDS_LOCATION"R4D3"
SEC"1"
SEC_TYPE"0402"
BOM_COST"SYS_CLOCK";
"B"
$PN"2"59;
"A"
$PN"1"72;
%"RES"
"1","(300,1575)","0","mstr_discrete","I69";
;
CDS_SEC"1"
WATTAGE"1/16W"
PACK_TYPE"0402"
TOLERANCE"1%"
MATERIAL"CHIP"
VALUE"27.4"
LOCATION"R4D29"
PART_NUMBER"G21796-182"
ROOM"DB1200Z"
CDS_LOCATION"R4D29"
SEC"1"
BOM_COST"SYS_CLOCK"
SEC_TYPE"0402"
CDS_LIB"mstr_discrete";
"B"
$PN"2"41;
"A"
$PN"1"49;
%"RES"
"1","(300,4825)","0","mstr_discrete","I74";
;
CDS_SEC"1"
VALUE"27.4"
WATTAGE"1/16W"
LOCATION"R4D6"
MATERIAL"CHIP"
PACK_TYPE"0402"
TOLERANCE"1%"
PART_NUMBER"G21796-182"
ROOM"DB1200Z"
CDS_LOCATION"R4D6"
SEC"1"
BOM_COST"SYS_CLOCK"
SEC_TYPE"0402"
CDS_LIB"mstr_discrete";
"B"
$PN"2"34;
"A"
$PN"1"50;
%"RES"
"1","(300,4500)","0","mstr_discrete","I79";
;
CDS_SEC"1"
VALUE"27.4"
WATTAGE"1/16W"
LOCATION"R4D5"
MATERIAL"CHIP"
PACK_TYPE"0402"
TOLERANCE"1%"
PART_NUMBER"G21796-182"
CDS_LOCATION"R4D5"
CDS_LIB"mstr_discrete"
SEC_TYPE"0402"
BOM_COST"SYS_CLOCK"
SEC"1"
ROOM"DB1200Z";
"B"
$PN"2"29;
"A"
$PN"1"30;
%"RES"
"1","(300,4175)","0","mstr_discrete","I84";
;
CDS_SEC"1"
WATTAGE"1/16W"
PACK_TYPE"0402"
TOLERANCE"1%"
VALUE"27.4"
LOCATION"R4D8"
MATERIAL"CHIP"
PART_NUMBER"G21796-182"
ROOM"DB1200Z"
CDS_LOCATION"R4D8"
SEC"1"
BOM_COST"SYS_CLOCK"
SEC_TYPE"0402"
CDS_LIB"mstr_discrete";
"B"
$PN"2"33;
"A"
$PN"1"51;
%"RES"
"1","(300,3850)","0","mstr_discrete","I89";
;
CDS_SEC"1"
VALUE"27.4"
WATTAGE"1/16W"
LOCATION"R4D7"
MATERIAL"CHIP"
PACK_TYPE"0402"
TOLERANCE"1%"
PART_NUMBER"G21796-182"
ROOM"DB1200Z"
CDS_LOCATION"R4D7"
SEC"1"
SEC_TYPE"0402"
CDS_LIB"mstr_discrete"
BOM_COST"SYS_CLOCK";
"B"
$PN"2"39;
"A"
$PN"1"26;
%"RES"
"1","(-3925,4900)","0","mstr_discrete","I9";
;
CDS_SEC"1"
LOCATION"R4D23"
VALUE"27.4"
WATTAGE"1/16W"
TOLERANCE"1%"
PART_NUMBER"G21796-182"
MATERIAL"CHIP"
PACK_TYPE"0402"
ROOM"DB1200Z"
CDS_LOCATION"R4D23"
CDS_LIB"mstr_discrete"
SEC"1"
SEC_TYPE"0402"
BOM_COST"SYS_CLOCK";
"B"
$PN"2"31;
"A"
$PN"1"62;
%"RES"
"1","(300,3525)","0","mstr_discrete","I94";
;
CDS_SEC"1"
VALUE"27.4"
WATTAGE"1/16W"
MATERIAL"CHIP"
PACK_TYPE"0402"
TOLERANCE"1%"
LOCATION"R4D12"
PART_NUMBER"G21796-182"
CDS_LIB"mstr_discrete"
CDS_LOCATION"R4D12"
BOM_COST"SYS_CLOCK"
SEC_TYPE"0402"
SEC"1"
ROOM"DB1200Z";
"B"
$PN"2"38;
"A"
$PN"1"52;
%"RES"
"1","(300,3200)","0","mstr_discrete","I99";
;
CDS_SEC"1"
VALUE"27.4"
WATTAGE"1/16W"
LOCATION"R4D10"
MATERIAL"CHIP"
PACK_TYPE"0402"
TOLERANCE"1%"
PART_NUMBER"G21796-182"
CDS_LOCATION"R4D10"
ROOM"DB1200Z"
BOM_COST"SYS_CLOCK"
SEC_TYPE"0402"
SEC"1"
CDS_LIB"mstr_discrete";
"B"
$PN"2"37;
"A"
$PN"1"43;
END.
